# T6G (Grand Teton) — schematic netlist excerpt (pin names and nets, part order shuffled) for the footprints in the layout excerpt that follows; sources: Cadence DE-HDL packaged netlist, KiCad conversion of 04192023_DAF0TMB3IC0_F0TG_MB_C_brd_V02_OCP.brd

C6600  Q_CAP_DIFFBUS  DIFF BUS_0.22UF 6.3V 20% X6S  pkg C0201  page 308 : \1\ = P5E_CPU0_P3_TX_BUF_C_DN<1> ; \2\ = P5E_CPU0_P3_TX_BUF_DN<1>
C2649  Q_CAP  22UF 4V 20% X6S  pkg C0402  page 70 : A = PVDDIO_P0 ; B = GND

(kicad_pcb
	(version 20260206)
	(generator "pcbnew")
	(generator_version "10.0")
	(general
		(thickness 1.6)
		(legacy_teardrops no)
	)
	(paper "A4")
	(title_block
		(title "04192023_DAF0TMB3IC0_F0TG_MB_C_brd_V02_OCP.brd")
		(comment 1 "Grand Teton / footprints 8279-8280 of 8354")
	)
	(layers
		(0 "F.Cu" signal "TOP")
		(4 "In1.Cu" signal "GND")
		(6 "In2.Cu" signal "IN1")
		(8 "In3.Cu" signal "GND1")
		(10 "In4.Cu" signal "IN2")
		(12 "In5.Cu" signal "GND2")
		(14 "In6.Cu" signal "IN3")
		(16 "In7.Cu" signal "GND3")
		(18 "In8.Cu" signal "VCC")
		(20 "In9.Cu" signal "VCC1")
		(22 "In10.Cu" signal "GND4")
		(24 "In11.Cu" signal "IN4")
		(26 "In12.Cu" signal "GND5")
		(28 "In13.Cu" signal "IN5")
		(30 "In14.Cu" signal "GND6")
		(32 "In15.Cu" signal "IN6")
		(34 "In16.Cu" signal "GND7")
		(2 "B.Cu" signal "BOTTOM")
		(9 "F.Adhes" user "F.Adhesive")
		(11 "B.Adhes" user "B.Adhesive")
		(13 "F.Paste" user "Package Geometry/Pastemask Top")
		(15 "B.Paste" user "Package Geometry/Pastemask Bottom")
		(5 "F.SilkS" user "Ref Des/Silkscreen Top")
		(7 "B.SilkS" user "Ref Des/Silkscreen Bottom")
		(1 "F.Mask" user "Board Geometry/Soldermask Top")
		(3 "B.Mask" user "Board Geometry/Soldermask Bottom")
		(17 "Dwgs.User" user "User.Drawings")
		(19 "Cmts.User" user "User.Comments")
		(21 "Eco1.User" user "User.Eco1")
		(23 "Eco2.User" user "User.Eco2")
		(25 "Edge.Cuts" user "Board Geometry/Outline")
		(27 "Margin" user)
		(31 "F.CrtYd" user "Package Geometry/Place Bound Top")
		(29 "B.CrtYd" user "Package Geometry/Place Bound Bottom")
		(35 "F.Fab" user "Ref Des/Assembly Top")
		(33 "B.Fab" user "Ref Des/Assembly Bottom")
	)
	(footprint ""
		(layer "B.Cu")
		(at 350.318832 -258.830064 180)
		(property "Reference" "C2649"
			(at 0 0 0)
			(layer "B.SilkS")
			(hide yes)
			(effects
				(font
					(size 1.27 1.27)
				)
				(justify mirror)
			)
		)
		(property "Value" ""
			(at 0 0 0)
			(layer "B.Fab")
			(effects
				(font
					(size 1.27 1.27)
				)
				(justify mirror)
			)
		)
		(duplicate_pad_numbers_are_jumpers no)
		(fp_line
			(start 0.7874 0.4064)
			(end 0.7874 -0.4064)
			(stroke
				(width 0.1524)
				(type default)
			)
			(layer "B.SilkS")
		)
		(fp_line
			(start 0.7874 -0.4064)
			(end -0.7874 -0.4064)
			(stroke
				(width 0.1524)
				(type default)
			)
			(layer "B.SilkS")
		)
		(fp_line
			(start -0.7874 0.4064)
			(end 0.7874 0.4064)
			(stroke
				(width 0.1524)
				(type default)
			)
			(layer "B.SilkS")
		)
		(fp_line
			(start -0.7874 -0.4064)
			(end -0.7874 0.4064)
			(stroke
				(width 0.1524)
				(type default)
			)
			(layer "B.SilkS")
		)
		(fp_line
			(start 0.67945 0.3048)
			(end 0.67945 -0.305054)
			(stroke
				(width 0.1)
				(type default)
			)
			(layer "B.Fab")
		)
		(fp_line
			(start 0.67945 -0.305054)
			(end 0.12065 -0.305054)
			(stroke
				(width 0.1)
				(type default)
			)
			(layer "B.Fab")
		)
		(fp_line
			(start 0.12065 0.3048)
			(end 0.67945 0.3048)
			(stroke
				(width 0.1)
				(type default)
			)
			(layer "B.Fab")
		)
		(fp_line
			(start 0.12065 0.2794)
			(end 0.12065 0.3048)
			(stroke
				(width 0.1)
				(type default)
			)
			(layer "B.Fab")
		)
		(fp_line
			(start 0.12065 -0.2794)
			(end -0.12065 -0.2794)
			(stroke
				(width 0.1)
				(type default)
			)
			(layer "B.Fab")
		)
		(fp_line
			(start 0.12065 -0.305054)
			(end 0.12065 -0.2794)
			(stroke
				(width 0.1)
				(type default)
			)
			(layer "B.Fab")
		)
		(fp_line
			(start -0.120396 0.3048)
			(end -0.120396 0.2794)
			(stroke
				(width 0.1)
				(type default)
			)
			(layer "B.Fab")
		)
		(fp_line
			(start -0.120396 0.2794)
			(end 0.12065 0.2794)
			(stroke
				(width 0.1)
				(type default)
			)
			(layer "B.Fab")
		)
		(fp_line
			(start -0.12065 -0.2794)
			(end -0.12065 -0.3048)
			(stroke
				(width 0.1)
				(type default)
			)
			(layer "B.Fab")
		)
		(fp_line
			(start -0.12065 -0.3048)
			(end -0.67945 -0.3048)
			(stroke
				(width 0.1)
				(type default)
			)
			(layer "B.Fab")
		)
		(fp_line
			(start -0.67945 0.3048)
			(end -0.120396 0.3048)
			(stroke
				(width 0.1)
				(type default)
			)
			(layer "B.Fab")
		)
		(fp_line
			(start -0.67945 -0.3048)
			(end -0.67945 0.3048)
			(stroke
				(width 0.1)
				(type default)
			)
			(layer "B.Fab")
		)
		(pad "1" smd circle
			(at 0.40005 0)
			(size 0 0)
			(layers "B.Cu" "B.Mask" "B.Paste")
			(net "PVDDIO_P0")
		)
		(pad "2" smd circle
			(at -0.40005 0)
			(size 0 0)
			(layers "B.Cu" "B.Mask" "B.Paste")
			(net "GND")
		)
	)
	(footprint ""
		(layer "B.Cu")
		(at 375.463562 -416.899344 90)
		(property "Reference" "C6600"
			(at 0 0 90)
			(layer "B.SilkS")
			(hide yes)
			(effects
				(font
					(size 1.27 1.27)
				)
				(justify mirror)
			)
		)
		(property "Value" ""
			(at 0 0 90)
			(layer "B.Fab")
			(effects
				(font
					(size 1.27 1.27)
				)
				(justify mirror)
			)
		)
		(duplicate_pad_numbers_are_jumpers no)
		(fp_line
			(start 0.299974 -0.150114)
			(end -0.299974 -0.150114)
			(stroke
				(width 0.1)
				(type default)
			)
			(layer "B.Fab")
		)
		(fp_line
			(start -0.299974 -0.150114)
			(end -0.299974 0.150114)
			(stroke
				(width 0.1)
				(type default)
			)
			(layer "B.Fab")
		)
		(fp_line
			(start 0.299974 0.150114)
			(end 0.299974 -0.150114)
			(stroke
				(width 0.1)
				(type default)
			)
			(layer "B.Fab")
		)
		(fp_line
			(start -0.299974 0.150114)
			(end 0.299974 0.150114)
			(stroke
				(width 0.1)
				(type default)
			)
			(layer "B.Fab")
		)
		(pad "1" smd rect
			(at 0.2667 0 270)
			(size 0.3048 0.381)
			(layers "B.Cu" "B.Mask" "B.Paste")
			(net "P5E_CPU0_P3_TX_BUF_C_DN<1>")
		)
		(pad "2" smd rect
			(at -0.2667 0 270)
			(size 0.3048 0.381)
			(layers "B.Cu" "B.Mask" "B.Paste")
			(net "P5E_CPU0_P3_TX_BUF_DN<1>")
		)
	)
)
